(kicad_pcb
	(version 20260206)
	(generator "pcbnew")
	(generator_version "10.0")
	(general
		(thickness 1.6)
		(legacy_teardrops no)
	)
	(paper "A4")
	(title_block
		(title "12092022_DA0F0TMDCD0_F0T_Management_Board_D_brd_V3_OCP.brd")
		(comment 1 "Grand Teton / footprints 1357-1361 of 1440")
	)
	(layers
		(0 "F.Cu" signal "TOP")
		(4 "In1.Cu" signal "GND")
		(6 "In2.Cu" signal "IN1")
		(8 "In3.Cu" signal "GND1")
		(10 "In4.Cu" signal "IN2")
		(12 "In5.Cu" signal "VCC")
		(14 "In6.Cu" signal "VCC1")
		(16 "In7.Cu" signal "IN3")
		(18 "In8.Cu" signal "GND2")
		(20 "In9.Cu" signal "IN4")
		(22 "In10.Cu" signal "GND3")
		(2 "B.Cu" signal "BOTTOM")
		(9 "F.Adhes" user "F.Adhesive")
		(11 "B.Adhes" user "B.Adhesive")
		(13 "F.Paste" user "Package Geometry/Pastemask Top")
		(15 "B.Paste" user "Package Geometry/Pastemask Bottom")
		(5 "F.SilkS" user "Ref Des/Silkscreen Top")
		(7 "B.SilkS" user "Ref Des/Silkscreen Bottom")
		(1 "F.Mask" user "Board Geometry/Soldermask Top")
		(3 "B.Mask" user "Board Geometry/Soldermask Bottom")
		(17 "Dwgs.User" user "User.Drawings")
		(19 "Cmts.User" user "User.Comments")
		(21 "Eco1.User" user "User.Eco1")
		(23 "Eco2.User" user "User.Eco2")
		(25 "Edge.Cuts" user "Board Geometry/Outline")
		(27 "Margin" user)
		(31 "F.CrtYd" user "Package Geometry/Place Bound Top")
		(29 "B.CrtYd" user "Package Geometry/Place Bound Bottom")
		(35 "F.Fab" user "Ref Des/Assembly Top")
		(33 "B.Fab" user "Ref Des/Assembly Bottom")
	)
	(footprint ""
		(layer "B.Cu")
		(at 34.925 -32.004 -90)
		(property "Reference" "L9"
			(at 0 0 90)
			(layer "B.SilkS")
			(hide yes)
			(effects
				(font
					(size 1.27 1.27)
				)
				(justify mirror)
			)
		)
		(property "Value" ""
			(at 0 0 90)
			(layer "B.Fab")
			(effects
				(font
					(size 1.27 1.27)
				)
				(justify mirror)
			)
		)
		(duplicate_pad_numbers_are_jumpers no)
		(fp_line
			(start -1.27 0.5842)
			(end 1.27 0.5842)
			(stroke
				(width 0.1524)
				(type default)
			)
			(layer "B.SilkS")
		)
		(fp_line
			(start -1.27 0.5842)
			(end -1.27 -0.5842)
			(stroke
				(width 0.1524)
				(type default)
			)
			(layer "B.SilkS")
		)
		(fp_line
			(start -0.127 0.5842)
			(end -0.127 -0.5842)
			(stroke
				(width 0.1524)
				(type default)
			)
			(layer "B.SilkS")
		)
		(fp_line
			(start 0.127 0.5842)
			(end 0.127 -0.5842)
			(stroke
				(width 0.1524)
				(type default)
			)
			(layer "B.SilkS")
		)
		(fp_line
			(start 1.27 0.5842)
			(end 1.27 -0.5842)
			(stroke
				(width 0.1524)
				(type default)
			)
			(layer "B.SilkS")
		)
		(fp_line
			(start 1.27 -0.5588)
			(end 1.27 -0.5842)
			(stroke
				(width 0.1524)
				(type default)
			)
			(layer "B.SilkS")
		)
		(fp_line
			(start 1.27 -0.5842)
			(end -1.27 -0.5842)
			(stroke
				(width 0.1524)
				(type default)
			)
			(layer "B.SilkS")
		)
		(fp_line
			(start -0.9144 0.508)
			(end 0.9144 0.508)
			(stroke
				(width 0.1)
				(type default)
			)
			(layer "B.Fab")
		)
		(fp_line
			(start 0.9144 0.508)
			(end 0.9144 0.406654)
			(stroke
				(width 0.1)
				(type default)
			)
			(layer "B.Fab")
		)
		(fp_line
			(start 0.9144 0.406654)
			(end 1.194308 0.406654)
			(stroke
				(width 0.1)
				(type default)
			)
			(layer "B.Fab")
		)
		(fp_line
			(start 1.194308 0.406654)
			(end 1.194308 -0.406654)
			(stroke
				(width 0.1)
				(type default)
			)
			(layer "B.Fab")
		)
		(fp_line
			(start -1.1938 0.4064)
			(end -0.9144 0.4064)
			(stroke
				(width 0.1)
				(type default)
			)
			(layer "B.Fab")
		)
		(fp_line
			(start -0.9144 0.4064)
			(end -0.9144 0.508)
			(stroke
				(width 0.1)
				(type default)
			)
			(layer "B.Fab")
		)
		(fp_line
			(start -1.1938 -0.406654)
			(end -1.1938 0.4064)
			(stroke
				(width 0.1)
				(type default)
			)
			(layer "B.Fab")
		)
		(fp_line
			(start -0.9144 -0.406654)
			(end -1.1938 -0.406654)
			(stroke
				(width 0.1)
				(type default)
			)
			(layer "B.Fab")
		)
		(fp_line
			(start 0.9144 -0.406654)
			(end 0.9144 -0.508)
			(stroke
				(width 0.1)
				(type default)
			)
			(layer "B.Fab")
		)
		(fp_line
			(start 1.194308 -0.406654)
			(end 0.9144 -0.406654)
			(stroke
				(width 0.1)
				(type default)
			)
			(layer "B.Fab")
		)
		(fp_line
			(start -0.9144 -0.508)
			(end -0.9144 -0.406654)
			(stroke
				(width 0.1)
				(type default)
			)
			(layer "B.Fab")
		)
		(fp_line
			(start 0.9144 -0.508)
			(end -0.9144 -0.508)
			(stroke
				(width 0.1)
				(type default)
			)
			(layer "B.Fab")
		)
		(pad "1" smd rect
			(at 0.7366 0 180)
			(size 0.7112 0.8128)
			(layers "B.Cu" "B.Mask" "B.Paste")
			(net "P3V3_AUX")
		)
		(pad "2" smd rect
			(at -0.7366 0 180)
			(size 0.7112 0.8128)
			(layers "B.Cu" "B.Mask" "B.Paste")
			(net "P3V3_STBY_PLLAHVDD")
		)
	)
	(footprint ""
		(layer "B.Cu")
		(at 40.4114 -58.097928)
		(property "Reference" "R566"
			(at 0 0 0)
			(layer "B.SilkS")
			(hide yes)
			(effects
				(font
					(size 1.27 1.27)
				)
				(justify mirror)
			)
		)
		(property "Value" ""
			(at 0 0 0)
			(layer "B.Fab")
			(effects
				(font
					(size 1.27 1.27)
				)
				(justify mirror)
			)
		)
		(duplicate_pad_numbers_are_jumpers no)
		(fp_line
			(start -0.7874 -0.4064)
			(end -0.7874 0.4064)
			(stroke
				(width 0.1524)
				(type default)
			)
			(layer "B.SilkS")
		)
		(fp_line
			(start -0.7874 0.4064)
			(end 0.7874 0.4064)
			(stroke
				(width 0.1524)
				(type default)
			)
			(layer "B.SilkS")
		)
		(fp_line
			(start 0.7874 -0.4064)
			(end -0.7874 -0.4064)
			(stroke
				(width 0.1524)
				(type default)
			)
			(layer "B.SilkS")
		)
		(fp_line
			(start 0.7874 0.4064)
			(end 0.7874 -0.4064)
			(stroke
				(width 0.1524)
				(type default)
			)
			(layer "B.SilkS")
		)
		(fp_line
			(start -0.67945 -0.3048)
			(end -0.67945 0.3048)
			(stroke
				(width 0.1)
				(type default)
			)
			(layer "B.Fab")
		)
		(fp_line
			(start -0.67945 0.3048)
			(end -0.120396 0.3048)
			(stroke
				(width 0.1)
				(type default)
			)
			(layer "B.Fab")
		)
		(fp_line
			(start -0.12065 -0.3048)
			(end -0.67945 -0.3048)
			(stroke
				(width 0.1)
				(type default)
			)
			(layer "B.Fab")
		)
		(fp_line
			(start -0.12065 -0.2794)
			(end -0.12065 -0.3048)
			(stroke
				(width 0.1)
				(type default)
			)
			(layer "B.Fab")
		)
		(fp_line
			(start -0.120396 0.2794)
			(end 0.12065 0.2794)
			(stroke
				(width 0.1)
				(type default)
			)
			(layer "B.Fab")
		)
		(fp_line
			(start -0.120396 0.3048)
			(end -0.120396 0.2794)
			(stroke
				(width 0.1)
				(type default)
			)
			(layer "B.Fab")
		)
		(fp_line
			(start 0.12065 -0.305054)
			(end 0.12065 -0.2794)
			(stroke
				(width 0.1)
				(type default)
			)
			(layer "B.Fab")
		)
		(fp_line
			(start 0.12065 -0.2794)
			(end -0.12065 -0.2794)
			(stroke
				(width 0.1)
				(type default)
			)
			(layer "B.Fab")
		)
		(fp_line
			(start 0.12065 0.2794)
			(end 0.12065 0.3048)
			(stroke
				(width 0.1)
				(type default)
			)
			(layer "B.Fab")
		)
		(fp_line
			(start 0.12065 0.3048)
			(end 0.67945 0.3048)
			(stroke
				(width 0.1)
				(type default)
			)
			(layer "B.Fab")
		)
		(fp_line
			(start 0.67945 -0.305054)
			(end 0.12065 -0.305054)
			(stroke
				(width 0.1)
				(type default)
			)
			(layer "B.Fab")
		)
		(fp_line
			(start 0.67945 0.3048)
			(end 0.67945 -0.305054)
			(stroke
				(width 0.1)
				(type default)
			)
			(layer "B.Fab")
		)
		(pad "1" smd circle
			(at 0.40005 0 180)
			(size 0 0)
			(layers "B.Cu" "B.Mask" "B.Paste")
			(net "RST_BMC_RSTBTN_OUT_R_N")
		)
		(pad "2" smd circle
			(at -0.40005 0 180)
			(size 0 0)
			(layers "B.Cu" "B.Mask" "B.Paste")
			(net "RST_BMC_RSTBTN_OUT_N")
		)
	)
	(footprint ""
		(layer "B.Cu")
		(at 57.04586 -50.94097)
		(property "Reference" "C92"
			(at 0 0 0)
			(layer "B.SilkS")
			(hide yes)
			(effects
				(font
					(size 1.27 1.27)
				)
				(justify mirror)
			)
		)
		(property "Value" ""
			(at 0 0 0)
			(layer "B.Fab")
			(effects
				(font
					(size 1.27 1.27)
				)
				(justify mirror)
			)
		)
		(duplicate_pad_numbers_are_jumpers no)
		(fp_line
			(start -0.7874 -0.4064)
			(end -0.7874 0.4064)
			(stroke
				(width 0.1524)
				(type default)
			)
			(layer "B.SilkS")
		)
		(fp_line
			(start -0.7874 0.4064)
			(end 0.7874 0.4064)
			(stroke
				(width 0.1524)
				(type default)
			)
			(layer "B.SilkS")
		)
		(fp_line
			(start 0.7874 -0.4064)
			(end -0.7874 -0.4064)
			(stroke
				(width 0.1524)
				(type default)
			)
			(layer "B.SilkS")
		)
		(fp_line
			(start 0.7874 0.4064)
			(end 0.7874 -0.4064)
			(stroke
				(width 0.1524)
				(type default)
			)
			(layer "B.SilkS")
		)
		(fp_line
			(start -0.67945 -0.3048)
			(end -0.67945 0.3048)
			(stroke
				(width 0.1)
				(type default)
			)
			(layer "B.Fab")
		)
		(fp_line
			(start -0.67945 0.3048)
			(end -0.120396 0.3048)
			(stroke
				(width 0.1)
				(type default)
			)
			(layer "B.Fab")
		)
		(fp_line
			(start -0.12065 -0.3048)
			(end -0.67945 -0.3048)
			(stroke
				(width 0.1)
				(type default)
			)
			(layer "B.Fab")
		)
		(fp_line
			(start -0.12065 -0.2794)
			(end -0.12065 -0.3048)
			(stroke
				(width 0.1)
				(type default)
			)
			(layer "B.Fab")
		)
		(fp_line
			(start -0.120396 0.2794)
			(end 0.12065 0.2794)
			(stroke
				(width 0.1)
				(type default)
			)
			(layer "B.Fab")
		)
		(fp_line
			(start -0.120396 0.3048)
			(end -0.120396 0.2794)
			(stroke
				(width 0.1)
				(type default)
			)
			(layer "B.Fab")
		)
		(fp_line
			(start 0.12065 -0.305054)
			(end 0.12065 -0.2794)
			(stroke
				(width 0.1)
				(type default)
			)
			(layer "B.Fab")
		)
		(fp_line
			(start 0.12065 -0.2794)
			(end -0.12065 -0.2794)
			(stroke
				(width 0.1)
				(type default)
			)
			(layer "B.Fab")
		)
		(fp_line
			(start 0.12065 0.2794)
			(end 0.12065 0.3048)
			(stroke
				(width 0.1)
				(type default)
			)
			(layer "B.Fab")
		)
		(fp_line
			(start 0.12065 0.3048)
			(end 0.67945 0.3048)
			(stroke
				(width 0.1)
				(type default)
			)
			(layer "B.Fab")
		)
		(fp_line
			(start 0.67945 -0.305054)
			(end 0.12065 -0.305054)
			(stroke
				(width 0.1)
				(type default)
			)
			(layer "B.Fab")
		)
		(fp_line
			(start 0.67945 0.3048)
			(end 0.67945 -0.305054)
			(stroke
				(width 0.1)
				(type default)
			)
			(layer "B.Fab")
		)
		(pad "1" smd circle
			(at 0.40005 0 180)
			(size 0 0)
			(layers "B.Cu" "B.Mask" "B.Paste")
			(net "P1V0_AUX")
		)
		(pad "2" smd circle
			(at -0.40005 0 180)
			(size 0 0)
			(layers "B.Cu" "B.Mask" "B.Paste")
			(net "GND")
		)
	)
	(footprint ""
		(layer "B.Cu")
		(at 27.3304 -85.7758)
		(property "Reference" "R837"
			(at 0 0 0)
			(layer "B.SilkS")
			(hide yes)
			(effects
				(font
					(size 1.27 1.27)
				)
				(justify mirror)
			)
		)
		(property "Value" ""
			(at 0 0 0)
			(layer "B.Fab")
			(effects
				(font
					(size 1.27 1.27)
				)
				(justify mirror)
			)
		)
		(duplicate_pad_numbers_are_jumpers no)
		(fp_line
			(start -0.7874 -0.4064)
			(end -0.7874 0.4064)
			(stroke
				(width 0.1524)
				(type default)
			)
			(layer "B.SilkS")
		)
		(fp_line
			(start -0.7874 0.4064)
			(end 0.7874 0.4064)
			(stroke
				(width 0.1524)
				(type default)
			)
			(layer "B.SilkS")
		)
		(fp_line
			(start 0.7874 -0.4064)
			(end -0.7874 -0.4064)
			(stroke
				(width 0.1524)
				(type default)
			)
			(layer "B.SilkS")
		)
		(fp_line
			(start 0.7874 0.4064)
			(end 0.7874 -0.4064)
			(stroke
				(width 0.1524)
				(type default)
			)
			(layer "B.SilkS")
		)
		(fp_line
			(start -0.67945 -0.3048)
			(end -0.67945 0.3048)
			(stroke
				(width 0.1)
				(type default)
			)
			(layer "B.Fab")
		)
		(fp_line
			(start -0.67945 0.3048)
			(end -0.120396 0.3048)
			(stroke
				(width 0.1)
				(type default)
			)
			(layer "B.Fab")
		)
		(fp_line
			(start -0.12065 -0.3048)
			(end -0.67945 -0.3048)
			(stroke
				(width 0.1)
				(type default)
			)
			(layer "B.Fab")
		)
		(fp_line
			(start -0.12065 -0.2794)
			(end -0.12065 -0.3048)
			(stroke
				(width 0.1)
				(type default)
			)
			(layer "B.Fab")
		)
		(fp_line
			(start -0.120396 0.2794)
			(end 0.12065 0.2794)
			(stroke
				(width 0.1)
				(type default)
			)
			(layer "B.Fab")
		)
		(fp_line
			(start -0.120396 0.3048)
			(end -0.120396 0.2794)
			(stroke
				(width 0.1)
				(type default)
			)
			(layer "B.Fab")
		)
		(fp_line
			(start 0.12065 -0.305054)
			(end 0.12065 -0.2794)
			(stroke
				(width 0.1)
				(type default)
			)
			(layer "B.Fab")
		)
		(fp_line
			(start 0.12065 -0.2794)
			(end -0.12065 -0.2794)
			(stroke
				(width 0.1)
				(type default)
			)
			(layer "B.Fab")
		)
		(fp_line
			(start 0.12065 0.2794)
			(end 0.12065 0.3048)
			(stroke
				(width 0.1)
				(type default)
			)
			(layer "B.Fab")
		)
		(fp_line
			(start 0.12065 0.3048)
			(end 0.67945 0.3048)
			(stroke
				(width 0.1)
				(type default)
			)
			(layer "B.Fab")
		)
		(fp_line
			(start 0.67945 -0.305054)
			(end 0.12065 -0.305054)
			(stroke
				(width 0.1)
				(type default)
			)
			(layer "B.Fab")
		)
		(fp_line
			(start 0.67945 0.3048)
			(end 0.67945 -0.305054)
			(stroke
				(width 0.1)
				(type default)
			)
			(layer "B.Fab")
		)
		(pad "1" smd circle
			(at 0.40005 0 180)
			(size 0 0)
			(layers "B.Cu" "B.Mask" "B.Paste")
			(net "PWRGD_PSU_AC_PWROK")
		)
		(pad "2" smd circle
			(at -0.40005 0 180)
			(size 0 0)
			(layers "B.Cu" "B.Mask" "B.Paste")
			(net "PWRGD_PSU_AC_PWROK_PLD")
		)
	)
	(footprint ""
		(layer "B.Cu")
		(at 16.637 -65.151 -90)
		(property "Reference" "U37"
			(at 1.397 -2.13233 270)
			(unlocked yes)
			(layer "B.SilkS")
			(effects
				(font
					(size 0.7874 0.5842)
					(thickness 0.1524)
				)
				(justify left mirror)
			)
		)
		(property "Value" ""
			(at 0 0 90)
			(layer "B.Fab")
			(effects
				(font
					(size 1.27 1.27)
				)
				(justify mirror)
			)
		)
		(duplicate_pad_numbers_are_jumpers no)
		(fp_line
			(start -1.3208 1.525016)
			(end 1.3208 1.525016)
			(stroke
				(width 0.1524)
				(type default)
			)
			(layer "B.SilkS")
		)
		(fp_line
			(start 1.3208 1.525016)
			(end 1.3208 -1.525016)
			(stroke
				(width 0.1524)
				(type default)
			)
			(layer "B.SilkS")
		)
		(fp_line
			(start 0 -0.999998)
			(end -0.508 -1.525016)
			(stroke
				(width 0.1524)
				(type default)
			)
			(layer "B.SilkS")
		)
		(fp_line
			(start -1.3208 -1.525016)
			(end -1.3208 1.525016)
			(stroke
				(width 0.1524)
				(type default)
			)
			(layer "B.SilkS")
		)
		(fp_line
			(start -0.508 -1.525016)
			(end -1.3208 -1.525016)
			(stroke
				(width 0.1524)
				(type default)
			)
			(layer "B.SilkS")
		)
		(fp_line
			(start 0.508 -1.525016)
			(end 0 -0.999998)
			(stroke
				(width 0.1524)
				(type default)
			)
			(layer "B.SilkS")
		)
		(fp_line
			(start 1.3208 -1.525016)
			(end 0.508 -1.525016)
			(stroke
				(width 0.1524)
				(type default)
			)
			(layer "B.SilkS")
		)
		(fp_poly
			(pts
				(xy 3.175 -1.016) (xy 3.937 -0.635) (xy 3.937 -1.397)
			)
			(stroke
				(width 0)
				(type default)
			)
			(fill yes)
			(layer "B.SilkS")
		)
		(fp_line
			(start -1.524 1.5494)
			(end 1.5494 1.5494)
			(stroke
				(width 0.1)
				(type default)
			)
			(layer "B.Fab")
		)
		(fp_line
			(start 1.5494 1.5494)
			(end 1.5494 1.203706)
			(stroke
				(width 0.1)
				(type default)
			)
			(layer "B.Fab")
		)
		(fp_line
			(start -3.0353 1.208786)
			(end -1.524 1.208786)
			(stroke
				(width 0.1)
				(type default)
			)
			(layer "B.Fab")
		)
		(fp_line
			(start -1.524 1.208786)
			(end -1.524 1.5494)
			(stroke
				(width 0.1)
				(type default)
			)
			(layer "B.Fab")
		)
		(fp_line
			(start 1.5494 1.203706)
			(end 3.037078 1.203706)
			(stroke
				(width 0.1)
				(type default)
			)
			(layer "B.Fab")
		)
		(fp_line
			(start 3.037078 1.203706)
			(end 3.037078 -1.20777)
			(stroke
				(width 0.1)
				(type default)
			)
			(layer "B.Fab")
		)
		(fp_line
			(start -3.0353 -1.20777)
			(end -3.0353 1.208786)
			(stroke
				(width 0.1)
				(type default)
			)
			(layer "B.Fab")
		)
		(fp_line
			(start -1.524 -1.20777)
			(end -3.0353 -1.20777)
			(stroke
				(width 0.1)
				(type default)
			)
			(layer "B.Fab")
		)
		(fp_line
			(start 1.524 -1.20777)
			(end 1.524 -1.524)
			(stroke
				(width 0.1)
				(type default)
			)
			(layer "B.Fab")
		)
		(fp_line
			(start 3.037078 -1.20777)
			(end 1.524 -1.20777)
			(stroke
				(width 0.1)
				(type default)
			)
			(layer "B.Fab")
		)
		(fp_line
			(start -1.524 -1.524)
			(end -1.524 -1.20777)
			(stroke
				(width 0.1)
				(type default)
			)
			(layer "B.Fab")
		)
		(fp_line
			(start 1.524 -1.524)
			(end -1.524 -1.524)
			(stroke
				(width 0.1)
				(type default)
			)
			(layer "B.Fab")
		)
		(fp_poly
			(pts
				(xy 3.175 -1.016) (xy 3.937 -0.635) (xy 3.937 -1.397)
			)
			(stroke
				(width 0)
				(type default)
			)
			(fill yes)
			(layer "B.Fab")
		)
		(pad "1" smd rect
			(at 2.234946 -0.975106 180)
			(size 0.3556 1.4986)
			(layers "B.Cu" "B.Mask" "B.Paste")
			(net "P3V3_AUX")
		)
		(pad "2" smd rect
			(at 2.234946 -0.32512 180)
			(size 0.3556 1.4986)
			(layers "B.Cu" "B.Mask" "B.Paste")
			(net "SMB_BMC_MM15_R1_SCL")
		)
		(pad "3" smd rect
			(at 2.234946 0.32512 180)
			(size 0.3556 1.4986)
			(layers "B.Cu" "B.Mask" "B.Paste")
			(net "SMB_BMC_MM15_R1_SDA")
		)
		(pad "4" smd rect
			(at 2.234946 0.975106 180)
			(size 0.3556 1.4986)
			(layers "B.Cu" "B.Mask" "B.Paste")
			(net "GND")
		)
		(pad "5" smd rect
			(at -2.234946 0.975106 180)
			(size 0.3556 1.4986)
			(layers "B.Cu" "B.Mask" "B.Paste")
			(net "DEBUG_PORT_PRSNT_BUF_EN")
		)
		(pad "6" smd rect
			(at -2.234946 0.32512 180)
			(size 0.3556 1.4986)
			(layers "B.Cu" "B.Mask" "B.Paste")
			(net "SMB_DEBUG_AUX_LVC3_USB_R1_SDA")
		)
		(pad "7" smd rect
			(at -2.234946 -0.32512 180)
			(size 0.3556 1.4986)
			(layers "B.Cu" "B.Mask" "B.Paste")
			(net "SMB_DEBUG_AUX_LVC3_USB_R1_SCL")
		)
		(pad "8" smd rect
			(at -2.234946 -0.975106 180)
			(size 0.3556 1.4986)
			(layers "B.Cu" "B.Mask" "B.Paste")
			(net "P3V3_AUX")
		)
	)
)
